# TIMECARD (Time Appliance Project (Time Card)) — schematic netlist excerpt (pin names and nets, part order shuffled) for the footprints in the layout excerpt that follows; sources: Cadence DE-HDL packaged netlist, KiCad conversion of R4006-B0001-02_R01.brd

R402  RESISTOR  2.2KOHM 1%  pkg SMC_0402R_H016  page 10 : \1\ = FPGA_TCK ; \2\ = SG
R428  RESISTOR  33OHM 1%  pkg SMC_0402R_H016  page 25 : \1\ = FPGA_IO_6 ; \2\ = UNNAMED_16_CONNHDR2X6FSSMT_I1_6

(kicad_pcb
	(version 20260206)
	(generator "pcbnew")
	(generator_version "10.0")
	(general
		(thickness 1.6)
		(legacy_teardrops no)
	)
	(paper "A4")
	(title_block
		(title "timecard-production-celestica-r4006 — R4006-B0001-02_R01.brd")
		(comment 1 "Time Appliance Project (Time Card) / footprints 1057-1058 of 1113")
	)
	(layers
		(0 "F.Cu" signal "TOP")
		(4 "In1.Cu" signal "L02_GND1")
		(6 "In2.Cu" signal "L03_SIG1")
		(8 "In3.Cu" signal "L04_GND2")
		(10 "In4.Cu" signal "L05_VCC1")
		(12 "In5.Cu" signal "L06_VCC2")
		(14 "In6.Cu" signal "L07_GND3")
		(16 "In7.Cu" signal "L08_SIG2")
		(18 "In8.Cu" signal "L09_GND4")
		(2 "B.Cu" signal "BOTTOM")
		(9 "F.Adhes" user "F.Adhesive")
		(11 "B.Adhes" user "B.Adhesive")
		(13 "F.Paste" user "Package Geometry/Pastemask Top")
		(15 "B.Paste" user "Package Geometry/Pastemask Bottom")
		(5 "F.SilkS" user "Ref Des/Silkscreen Top")
		(7 "B.SilkS" user "Ref Des/Silkscreen Bottom")
		(1 "F.Mask" user "Board Geometry/Soldermask Top")
		(3 "B.Mask" user "Board Geometry/Soldermask Bottom")
		(17 "Dwgs.User" user "User.Drawings")
		(19 "Cmts.User" user "User.Comments")
		(21 "Eco1.User" user "User.Eco1")
		(23 "Eco2.User" user "User.Eco2")
		(25 "Edge.Cuts" user "Board Geometry/Outline")
		(27 "Margin" user)
		(31 "F.CrtYd" user "Package Geometry/Place Bound Top")
		(29 "B.CrtYd" user "Package Geometry/Place Bound Bottom")
		(35 "F.Fab" user "Ref Des/Assembly Top")
		(33 "B.Fab" user "Ref Des/Assembly Bottom")
	)
	(footprint ""
		(layer "B.Cu")
		(at 156.718 -39.497 -90)
		(property "Reference" "R428"
			(at 6.77037 0.635 0)
			(unlocked yes)
			(layer "B.SilkS")
			(effects
				(font
					(size 0.7874 0.5842)
					(thickness 0.1524)
				)
				(justify mirror)
			)
		)
		(property "Value" "VAL*"
			(at -0.02032 2.13233 270)
			(unlocked yes)
			(layer "B.Fab")
			(hide yes)
			(effects
				(font
					(size 0.7874 0.5842)
					(thickness 0.1524)
				)
				(justify mirror)
			)
		)
		(property "Tolerance" "TOL*"
			(at -0.044704 3.05435 270)
			(unlocked yes)
			(layer "Cmts.User")
			(hide yes)
			(effects
				(font
					(size 0.7874 0.5842)
					(thickness 0.1524)
				)
				(justify mirror)
			)
		)
		(property "User Part Number" "PARTNUM*"
			(at -0.02032 4.024884 270)
			(unlocked yes)
			(layer "Cmts.User")
			(hide yes)
			(effects
				(font
					(size 0.7874 0.5842)
					(thickness 0.1524)
				)
				(justify mirror)
			)
		)
		(property "Device Type" "RESISTOR-G155-133R0-01,33OHM,1%"
			(at -0.008382 1.210564 270)
			(unlocked yes)
			(layer "B.Fab")
			(hide yes)
			(effects
				(font
					(size 0.7874 0.5842)
					(thickness 0.1524)
				)
				(justify mirror)
			)
		)
		(duplicate_pad_numbers_are_jumpers no)
		(fp_line
			(start -1.143 0.5588)
			(end -1.143 -0.5588)
			(stroke
				(width 0.1)
				(type default)
			)
			(layer "B.SilkS")
		)
		(fp_line
			(start 1.143 0.5588)
			(end -1.143 0.5588)
			(stroke
				(width 0.1)
				(type default)
			)
			(layer "B.SilkS")
		)
		(fp_line
			(start -1.143 -0.5588)
			(end 1.143 -0.5588)
			(stroke
				(width 0.1)
				(type default)
			)
			(layer "B.SilkS")
		)
		(fp_line
			(start 1.143 -0.5588)
			(end 1.143 0.5588)
			(stroke
				(width 0.1)
				(type default)
			)
			(layer "B.SilkS")
		)
		(fp_poly
			(pts
				(xy 1.143 0.5588) (xy -1.143 0.5588) (xy -1.143 -0.5588) (xy 1.143 -0.5588)
			)
			(stroke
				(width 0)
				(type default)
			)
			(fill no)
			(layer "B.CrtYd")
		)
		(fp_line
			(start -0.508 0.3048)
			(end -0.508 -0.3048)
			(stroke
				(width 0.1)
				(type default)
			)
			(layer "B.Fab")
		)
		(fp_line
			(start 0.508 0.3048)
			(end -0.508 0.3048)
			(stroke
				(width 0.1)
				(type default)
			)
			(layer "B.Fab")
		)
		(fp_line
			(start -0.508 -0.3048)
			(end 0.508 -0.3048)
			(stroke
				(width 0.1)
				(type default)
			)
			(layer "B.Fab")
		)
		(fp_line
			(start 0.508 -0.3048)
			(end 0.508 0.3048)
			(stroke
				(width 0.1)
				(type default)
			)
			(layer "B.Fab")
		)
		(pad "1" smd rect
			(at 0.5334 0 90)
			(size 0.7112 0.6096)
			(layers "B.Cu" "B.Mask" "B.Paste")
			(net "FPGA_IO_6")
		)
		(pad "2" smd rect
			(at -0.5334 0 90)
			(size 0.7112 0.6096)
			(layers "B.Cu" "B.Mask" "B.Paste")
			(net "UNNAMED_16_CONNHDR2X6FSSMT_I1_6")
		)
		(zone
			(layer "B.Cu")
			(hatch none 0.5)
			(connect_pads
				(clearance 0)
			)
			(min_thickness 0.25)
			(keepout
				(tracks not_allowed)
				(vias allowed)
				(pads allowed)
				(copperpour not_allowed)
				(footprints allowed)
			)
			(placement
				(enabled no)
				(sheetname "")
			)
			(fill
				(thermal_gap 0.5)
				(thermal_bridge_width 0.5)
				(island_removal_mode 0)
			)
			(polygon
				(pts
					(xy 156.4132 -39.4208) (xy 157.0228 -39.4208) (xy 157.0228 -39.5732) (xy 156.4132 -39.5732)
				)
			)
		)
		(zone
			(layer "B.Cu")
			(hatch none 0.5)
			(connect_pads
				(clearance 0)
			)
			(min_thickness 0.25)
			(keepout
				(tracks allowed)
				(vias not_allowed)
				(pads allowed)
				(copperpour not_allowed)
				(footprints allowed)
			)
			(placement
				(enabled no)
				(sheetname "")
			)
			(fill
				(thermal_gap 0.5)
				(thermal_bridge_width 0.5)
				(island_removal_mode 0)
			)
			(polygon
				(pts
					(xy 156.4132 -39.4208) (xy 157.0228 -39.4208) (xy 157.0228 -39.5732) (xy 156.4132 -39.5732)
				)
			)
		)
	)
	(footprint ""
		(layer "B.Cu")
		(at 138.4935 -67.5259 -90)
		(property "Reference" "R402"
			(at 0.8509 1.24587 270)
			(unlocked yes)
			(layer "B.SilkS")
			(effects
				(font
					(size 0.7874 0.5842)
					(thickness 0.1524)
				)
				(justify mirror)
			)
		)
		(property "Value" "VAL*"
			(at -0.02032 2.13233 270)
			(unlocked yes)
			(layer "B.Fab")
			(hide yes)
			(effects
				(font
					(size 0.7874 0.5842)
					(thickness 0.1524)
				)
				(justify mirror)
			)
		)
		(property "Device Type" "RESISTOR-G155-14701-01,4.7KOHMA"
			(at -0.008382 1.210564 270)
			(unlocked yes)
			(layer "B.Fab")
			(hide yes)
			(effects
				(font
					(size 0.7874 0.5842)
					(thickness 0.1524)
				)
				(justify mirror)
			)
		)
		(property "User Part Number" "PARTNUM*"
			(at -0.02032 4.024884 270)
			(unlocked yes)
			(layer "Cmts.User")
			(hide yes)
			(effects
				(font
					(size 0.7874 0.5842)
					(thickness 0.1524)
				)
				(justify mirror)
			)
		)
		(property "Tolerance" "TOL*"
			(at -0.044704 3.05435 270)
			(unlocked yes)
			(layer "Cmts.User")
			(hide yes)
			(effects
				(font
					(size 0.7874 0.5842)
					(thickness 0.1524)
				)
				(justify mirror)
			)
		)
		(duplicate_pad_numbers_are_jumpers no)
		(fp_line
			(start -1.143 0.5588)
			(end -1.143 -0.5588)
			(stroke
				(width 0.1)
				(type default)
			)
			(layer "B.SilkS")
		)
		(fp_line
			(start 1.143 0.5588)
			(end -1.143 0.5588)
			(stroke
				(width 0.1)
				(type default)
			)
			(layer "B.SilkS")
		)
		(fp_line
			(start -1.143 -0.5588)
			(end 1.143 -0.5588)
			(stroke
				(width 0.1)
				(type default)
			)
			(layer "B.SilkS")
		)
		(fp_line
			(start 1.143 -0.5588)
			(end 1.143 0.5588)
			(stroke
				(width 0.1)
				(type default)
			)
			(layer "B.SilkS")
		)
		(fp_rect
			(start 1.143 0.5588)
			(end -1.143 -0.5588)
			(stroke
				(width 0)
				(type default)
			)
			(fill no)
			(layer "B.CrtYd")
		)
		(fp_line
			(start -0.508 0.3048)
			(end -0.508 -0.3048)
			(stroke
				(width 0.1)
				(type default)
			)
			(layer "B.Fab")
		)
		(fp_line
			(start 0.508 0.3048)
			(end -0.508 0.3048)
			(stroke
				(width 0.1)
				(type default)
			)
			(layer "B.Fab")
		)
		(fp_line
			(start -0.508 -0.3048)
			(end 0.508 -0.3048)
			(stroke
				(width 0.1)
				(type default)
			)
			(layer "B.Fab")
		)
		(fp_line
			(start 0.508 -0.3048)
			(end 0.508 0.3048)
			(stroke
				(width 0.1)
				(type default)
			)
			(layer "B.Fab")
		)
		(pad "1" smd rect
			(at 0.5334 0 90)
			(size 0.7112 0.6096)
			(layers "B.Cu" "B.Mask" "B.Paste")
			(net "FPGA_TCK")
		)
		(pad "2" smd rect
			(at -0.5334 0 90)
			(size 0.7112 0.6096)
			(layers "B.Cu" "B.Mask" "B.Paste")
			(net "SG")
		)
		(zone
			(layer "B.Cu")
			(hatch none 0.5)
			(connect_pads
				(clearance 0)
			)
			(min_thickness 0.25)
			(keepout
				(tracks allowed)
				(vias not_allowed)
				(pads allowed)
				(copperpour not_allowed)
				(footprints allowed)
			)
			(placement
				(enabled no)
				(sheetname "")
			)
			(fill
				(thermal_gap 0.5)
				(thermal_bridge_width 0.5)
				(island_removal_mode 0)
			)
			(polygon
				(pts
					(xy 138.1887 -67.4497) (xy 138.7983 -67.4497) (xy 138.7983 -67.6021) (xy 138.1887 -67.6021)
				)
			)
		)
		(zone
			(layer "B.Cu")
			(hatch none 0.5)
			(connect_pads
				(clearance 0)
			)
			(min_thickness 0.25)
			(keepout
				(tracks not_allowed)
				(vias allowed)
				(pads allowed)
				(copperpour not_allowed)
				(footprints allowed)
			)
			(placement
				(enabled no)
				(sheetname "")
			)
			(fill
				(thermal_gap 0.5)
				(thermal_bridge_width 0.5)
				(island_removal_mode 0)
			)
			(polygon
				(pts
					(xy 138.1887 -67.4497) (xy 138.7983 -67.4497) (xy 138.7983 -67.6021) (xy 138.1887 -67.6021)
				)
			)
		)
	)
)
